#ISCELL
  mstr_misc dns *
  *
#ISCELL
  mstr_symbols intel_corp_bpage *
  *
#ISCELL
  mstr_symbols pvddq_klm *
  page228_i109
#CELL
  mstr_discrete cap *
  page228_i110
#ISCELL
  mstr_symbols gnd *
  page228_i114
#ISCELL
  mstr_symbols vcc_core *
  page228_i120
#ISCELL
  mstr_symbols gnd *
  page228_i123
#CELL
  mstr_discrete inductor *
  page228_i124
#CELL
  mstr_discrete capp *
  page228_i175
#ISCELL
  mstr_symbols p12v_stby *
  page228_i182
#CELL
  mstr_discrete cap *
  page228_i183
#CELL
  mstr_discrete cap *
  page228_i185
#CELL
  mstr_discrete cap *
  page228_i186
#CELL
  mstr_discrete cap *
  page228_i187
#CELL
  mstr_discrete cap *
  page228_i188
#ISCELL
  mstr_symbols gnd *
  page228_i189
#CELL
  mstr_discrete cap *
  page228_i190
#ISCELL
  mstr_symbols pvddq_klm *
  page228_i191
#ISCELL
  mstr_symbols pvddq_klm *
  page228_i195
#ISCELL
  mstr_symbols gnd *
  page228_i197
#CELL
  dev_discrete cap_a *
  page228_i198
#CELL
  dev_discrete cap_a *
  page228_i199
#CELL
  dev_discrete cap_a *
  page228_i200
#CELL
  dev_discrete cap_a *
  page228_i201
#CELL
  dev_discrete cap_a *
  page228_i202
#CELL
  dev_discrete cap_a *
  page228_i203
#CELL
  dev_discrete cap_a *
  page228_i204
#CELL
  dev_discrete cap_a *
  page228_i205
#CELL
  dev_discrete cap_a *
  page228_i206
#ISCELL
  mstr_symbols pvddq_klm *
  page228_i207
#ISCELL
  mstr_symbols gnd *
  page228_i208
#CELL
  dev_discrete cap_a *
  page228_i209
#CELL
  dev_discrete cap_a *
  page228_i210
#CELL
  dev_discrete cap_a *
  page228_i211
#CELL
  dev_discrete cap_a *
  page228_i212
#CELL
  dev_discrete cap_a *
  page228_i213
#CELL
  dev_discrete cap_a *
  page228_i214
#CELL
  dev_discrete cap_a *
  page228_i215
#CELL
  dev_discrete cap_a *
  page228_i216
#CELL
  dev_discrete cap_a *
  page228_i217
#CELL
  dev_discrete cap_a *
  page228_i218
#CELL
  dev_discrete cap_a *
  page228_i219
#CELL
  dev_discrete cap_a *
  page228_i220
#CELL
  dev_discrete cap_a *
  page228_i221
#CELL
  dev_discrete cap_a *
  page228_i222
#CELL
  dev_discrete cap_a *
  page228_i223
#ISCELL
  mstr_symbols pvddq_klm *
  page228_i224
#CELL
  dev_discrete cap_a *
  page228_i225
#ISCELL
  mstr_symbols gnd *
  page228_i226
#CELL
  dev_discrete cap_a *
  page228_i227
#CELL
  dev_discrete cap_a *
  page228_i228
#CELL
  dev_discrete cap_a *
  page228_i229
#CELL
  dev_discrete cap_a *
  page228_i230
#CELL
  dev_discrete cap_a *
  page228_i231
#CELL
  dev_discrete cap_a *
  page228_i232
#CELL
  dev_discrete cap_a *
  page228_i233
#CELL
  dev_discrete cap_a *
  page228_i234
#CELL
  dev_discrete cap_a *
  page228_i235
#CELL
  dev_discrete cap_a *
  page228_i236
#CELL
  dev_discrete cap_a *
  page228_i237
#CELL
  dev_discrete cap_a *
  page228_i238
#CELL
  dev_discrete cap_a *
  page228_i239
#CELL
  dev_discrete cap_a *
  page228_i240
#CELL
  dev_discrete cap_a *
  page228_i241
#ISCELL
  mstr_symbols pvddq_klm *
  page228_i242
#CELL
  dev_discrete cap_a *
  page228_i243
#ISCELL
  mstr_symbols gnd *
  page228_i244
#CELL
  mstr_misc shunt *
  page228_i245
#CELL
  mstr_misc shunt *
  page228_i246
#CELL
  mstr_discrete res *
  page228_i58
#ISCELL
  mstr_symbols gnd *
  page228_i65
#ISCELL
  mstr_standard offpage *
  page228_i70
#ISCELL
  mstr_standard offpage *
  page228_i72
#ISCELL
  mstr_symbols pvddq_klm *
  page228_i73
#CELL
  mstr_discrete res *
  page228_i74
#CELL
  mstr_discrete capp *
  page228_i75
#CELL
  mstr_discrete capp *
  page228_i76
#CELL
  mstr_discrete capp *
  page228_i77
#CELL
  mstr_discrete capp *
  page228_i78
#ISCELL
  mstr_symbols pvddq_klm *
  page228_i80
#ISCELL
  mstr_symbols gnd *
  page228_i81
#CELL
  mstr_discrete cap *
  page228_i82
#CELL
  mstr_discrete cap *
  page228_i83
#CELL
  mstr_discrete cap *
  page228_i88
#CELL
  mstr_discrete cap *
  page228_i89
#CELL
  mstr_discrete cap *
  page228_i90
#CELL
  mstr_discrete cap *
  page228_i91
#CELL
  mstr_discrete cap *
  page228_i92
#ISCELL
  mstr_symbols pvddq_klm *
  page228_i93
#ISCELL
  mstr_symbols gnd *
  page228_i94
